# S9S_MB_2U (Grand Teton) — schematic netlist excerpt (pin names and nets, part order shuffled) for the footprints in the layout excerpt that follows; sources: Cadence DE-HDL packaged netlist, KiCad conversion of 03242023_DA0F0TMBIJ0_F0T_Motherboard_J_brd_V01_OCP.brd

R3268  Q_RES  68K 1% EMPTY  pkg 0402LF  page 166 : A = FM_P2E_EQA1 ; B = GND
C282  Q_CAP  22UF 4V 20% X6S  pkg C0402  page 77 : A = PVCCIN_CPU1 ; B = GND

(kicad_pcb
	(version 20260206)
	(generator "pcbnew")
	(generator_version "10.0")
	(general
		(thickness 1.6)
		(legacy_teardrops no)
	)
	(paper "A4")
	(title_block
		(title "03242023_DA0F0TMBIJ0_F0T_Motherboard_J_brd_V01_OCP.brd")
		(comment 1 "Grand Teton / footprints 2114-2115 of 6105")
	)
	(layers
		(0 "F.Cu" signal "TOP")
		(4 "In1.Cu" signal "GND")
		(6 "In2.Cu" signal "IN1")
		(8 "In3.Cu" signal "GND1")
		(10 "In4.Cu" signal "IN2")
		(12 "In5.Cu" signal "GND2")
		(14 "In6.Cu" signal "IN3")
		(16 "In7.Cu" signal "GND3")
		(18 "In8.Cu" signal "VCC")
		(20 "In9.Cu" signal "VCC1")
		(22 "In10.Cu" signal "GND4")
		(24 "In11.Cu" signal "IN4")
		(26 "In12.Cu" signal "GND5")
		(28 "In13.Cu" signal "IN5")
		(30 "In14.Cu" signal "GND6")
		(32 "In15.Cu" signal "IN6")
		(34 "In16.Cu" signal "GND7")
		(2 "B.Cu" signal "BOTTOM")
		(9 "F.Adhes" user "F.Adhesive")
		(11 "B.Adhes" user "B.Adhesive")
		(13 "F.Paste" user "Package Geometry/Pastemask Top")
		(15 "B.Paste" user "Package Geometry/Pastemask Bottom")
		(5 "F.SilkS" user "Ref Des/Silkscreen Top")
		(7 "B.SilkS" user "Ref Des/Silkscreen Bottom")
		(1 "F.Mask" user "Board Geometry/Soldermask Top")
		(3 "B.Mask" user "Board Geometry/Soldermask Bottom")
		(17 "Dwgs.User" user "User.Drawings")
		(19 "Cmts.User" user "User.Comments")
		(21 "Eco1.User" user "User.Eco1")
		(23 "Eco2.User" user "User.Eco2")
		(25 "Edge.Cuts" user "Board Geometry/Outline")
		(27 "Margin" user)
		(31 "F.CrtYd" user "Package Geometry/Place Bound Top")
		(29 "B.CrtYd" user "Package Geometry/Place Bound Bottom")
		(35 "F.Fab" user "Ref Des/Assembly Top")
		(33 "B.Fab" user "Ref Des/Assembly Bottom")
	)
	(footprint ""
		(layer "F.Cu")
		(at 15.436596 -395.247876 180)
		(property "Reference" "R3268"
			(at 0 0 180)
			(layer "F.SilkS")
			(hide yes)
			(effects
				(font
					(size 1.27 1.27)
				)
			)
		)
		(property "Value" ""
			(at 0 0 180)
			(layer "F.Fab")
			(effects
				(font
					(size 1.27 1.27)
				)
			)
		)
		(duplicate_pad_numbers_are_jumpers no)
		(fp_line
			(start 0.7874 0.4064)
			(end -0.7874 0.4064)
			(stroke
				(width 0.1524)
				(type default)
			)
			(layer "F.SilkS")
		)
		(fp_line
			(start 0.7874 -0.4064)
			(end 0.7874 0.4064)
			(stroke
				(width 0.1524)
				(type default)
			)
			(layer "F.SilkS")
		)
		(fp_line
			(start -0.7874 0.4064)
			(end -0.7874 -0.4064)
			(stroke
				(width 0.1524)
				(type default)
			)
			(layer "F.SilkS")
		)
		(fp_line
			(start -0.7874 -0.4064)
			(end 0.7874 -0.4064)
			(stroke
				(width 0.1524)
				(type default)
			)
			(layer "F.SilkS")
		)
		(fp_line
			(start 0.67945 0.3048)
			(end 0.120396 0.3048)
			(stroke
				(width 0.1)
				(type default)
			)
			(layer "F.Fab")
		)
		(fp_line
			(start 0.67945 -0.3048)
			(end 0.67945 0.3048)
			(stroke
				(width 0.1)
				(type default)
			)
			(layer "F.Fab")
		)
		(fp_line
			(start 0.12065 -0.2794)
			(end 0.12065 -0.3048)
			(stroke
				(width 0.1)
				(type default)
			)
			(layer "F.Fab")
		)
		(fp_line
			(start 0.12065 -0.3048)
			(end 0.67945 -0.3048)
			(stroke
				(width 0.1)
				(type default)
			)
			(layer "F.Fab")
		)
		(fp_line
			(start 0.120396 0.3048)
			(end 0.120396 0.2794)
			(stroke
				(width 0.1)
				(type default)
			)
			(layer "F.Fab")
		)
		(fp_line
			(start 0.120396 0.2794)
			(end -0.12065 0.2794)
			(stroke
				(width 0.1)
				(type default)
			)
			(layer "F.Fab")
		)
		(fp_line
			(start -0.12065 0.3048)
			(end -0.67945 0.3048)
			(stroke
				(width 0.1)
				(type default)
			)
			(layer "F.Fab")
		)
		(fp_line
			(start -0.12065 0.2794)
			(end -0.12065 0.3048)
			(stroke
				(width 0.1)
				(type default)
			)
			(layer "F.Fab")
		)
		(fp_line
			(start -0.12065 -0.2794)
			(end 0.12065 -0.2794)
			(stroke
				(width 0.1)
				(type default)
			)
			(layer "F.Fab")
		)
		(fp_line
			(start -0.12065 -0.305054)
			(end -0.12065 -0.2794)
			(stroke
				(width 0.1)
				(type default)
			)
			(layer "F.Fab")
		)
		(fp_line
			(start -0.67945 0.3048)
			(end -0.67945 -0.305054)
			(stroke
				(width 0.1)
				(type default)
			)
			(layer "F.Fab")
		)
		(fp_line
			(start -0.67945 -0.305054)
			(end -0.12065 -0.305054)
			(stroke
				(width 0.1)
				(type default)
			)
			(layer "F.Fab")
		)
		(pad "1" smd circle
			(at -0.40005 0 180)
			(size 0 0)
			(layers "F.Cu" "F.Mask" "F.Paste")
			(net "FM_P2E_EQA1")
		)
		(pad "2" smd circle
			(at 0.40005 0 180)
			(size 0 0)
			(layers "F.Cu" "F.Mask" "F.Paste")
			(net "GND")
		)
	)
	(footprint ""
		(layer "F.Cu")
		(at 116.561616 -247.715278 90)
		(property "Reference" "C282"
			(at 0 0 90)
			(layer "F.SilkS")
			(hide yes)
			(effects
				(font
					(size 1.27 1.27)
				)
			)
		)
		(property "Value" ""
			(at 0 0 90)
			(layer "F.Fab")
			(effects
				(font
					(size 1.27 1.27)
				)
			)
		)
		(duplicate_pad_numbers_are_jumpers no)
		(fp_line
			(start 0.7874 -0.4064)
			(end 0.7874 0.4064)
			(stroke
				(width 0.1524)
				(type default)
			)
			(layer "F.SilkS")
		)
		(fp_line
			(start -0.7874 -0.4064)
			(end 0.7874 -0.4064)
			(stroke
				(width 0.1524)
				(type default)
			)
			(layer "F.SilkS")
		)
		(fp_line
			(start 0.7874 0.4064)
			(end -0.7874 0.4064)
			(stroke
				(width 0.1524)
				(type default)
			)
			(layer "F.SilkS")
		)
		(fp_line
			(start -0.7874 0.4064)
			(end -0.7874 -0.4064)
			(stroke
				(width 0.1524)
				(type default)
			)
			(layer "F.SilkS")
		)
		(fp_line
			(start -0.12065 -0.305054)
			(end -0.12065 -0.2794)
			(stroke
				(width 0.1)
				(type default)
			)
			(layer "F.Fab")
		)
		(fp_line
			(start -0.67945 -0.305054)
			(end -0.12065 -0.305054)
			(stroke
				(width 0.1)
				(type default)
			)
			(layer "F.Fab")
		)
		(fp_line
			(start 0.67945 -0.3048)
			(end 0.67945 0.3048)
			(stroke
				(width 0.1)
				(type default)
			)
			(layer "F.Fab")
		)
		(fp_line
			(start 0.12065 -0.3048)
			(end 0.67945 -0.3048)
			(stroke
				(width 0.1)
				(type default)
			)
			(layer "F.Fab")
		)
		(fp_line
			(start 0.12065 -0.2794)
			(end 0.12065 -0.3048)
			(stroke
				(width 0.1)
				(type default)
			)
			(layer "F.Fab")
		)
		(fp_line
			(start -0.12065 -0.2794)
			(end 0.12065 -0.2794)
			(stroke
				(width 0.1)
				(type default)
			)
			(layer "F.Fab")
		)
		(fp_line
			(start 0.120396 0.2794)
			(end -0.12065 0.2794)
			(stroke
				(width 0.1)
				(type default)
			)
			(layer "F.Fab")
		)
		(fp_line
			(start -0.12065 0.2794)
			(end -0.12065 0.3048)
			(stroke
				(width 0.1)
				(type default)
			)
			(layer "F.Fab")
		)
		(fp_line
			(start 0.67945 0.3048)
			(end 0.120396 0.3048)
			(stroke
				(width 0.1)
				(type default)
			)
			(layer "F.Fab")
		)
		(fp_line
			(start 0.120396 0.3048)
			(end 0.120396 0.2794)
			(stroke
				(width 0.1)
				(type default)
			)
			(layer "F.Fab")
		)
		(fp_line
			(start -0.12065 0.3048)
			(end -0.67945 0.3048)
			(stroke
				(width 0.1)
				(type default)
			)
			(layer "F.Fab")
		)
		(fp_line
			(start -0.67945 0.3048)
			(end -0.67945 -0.305054)
			(stroke
				(width 0.1)
				(type default)
			)
			(layer "F.Fab")
		)
		(pad "1" smd circle
			(at -0.40005 0 90)
			(size 0 0)
			(layers "F.Cu" "F.Mask" "F.Paste")
			(net "PVCCIN_CPU1")
		)
		(pad "2" smd circle
			(at 0.40005 0 90)
			(size 0 0)
			(layers "F.Cu" "F.Mask" "F.Paste")
			(net "GND")
		)
	)
)
